# BASEBOARD_FAB2 (Tioga Pass) — schematic netlist excerpt (pin names and nets, part order shuffled) for the footprints in the layout excerpt that follows; sources: Cadence DE-HDL packaged netlist, KiCad conversion of Wiwynn_Tioga_Pass_MB.brd

R1L11  RES  10.0 1% CHIP  pkg 0402  page 155 : A = LED_POSTCODE_7 ; B = LED_POSTCODE_7_R
R1U46  RES  33.2 1% CHIP  pkg 0402  page 152 : A = H_CPU0_MEMABC_MEMHOT_LVT3_K_N ; B = H_CPU0_MEMABC_MEMHOT_LVT3_N

(kicad_pcb
	(version 20260206)
	(generator "pcbnew")
	(generator_version "10.0")
	(general
		(thickness 1.6)
		(legacy_teardrops no)
	)
	(paper "A4")
	(title_block
		(title "Wiwynn_Tioga_Pass_MB.brd")
		(comment 1 "Tioga Pass / footprints 4363-4365 of 4770")
	)
	(layers
		(0 "F.Cu" signal "TOP")
		(4 "In1.Cu" signal "L2GND")
		(6 "In2.Cu" signal "L3")
		(8 "In3.Cu" signal "L4GND")
		(10 "In4.Cu" signal "L5")
		(12 "In5.Cu" signal "L6GND")
		(14 "In6.Cu" signal "L7VCC")
		(16 "In7.Cu" signal "L8VCC")
		(18 "In8.Cu" signal "L9GND")
		(20 "In9.Cu" signal "L10")
		(22 "In10.Cu" signal "L11GND")
		(24 "In11.Cu" signal "L12")
		(26 "In12.Cu" signal "L13GND")
		(2 "B.Cu" signal "BOTTOM")
		(9 "F.Adhes" user "F.Adhesive")
		(11 "B.Adhes" user "B.Adhesive")
		(13 "F.Paste" user "Package Geometry/Pastemask Top")
		(15 "B.Paste" user "Package Geometry/Pastemask Bottom")
		(5 "F.SilkS" user "Ref Des/Silkscreen Top")
		(7 "B.SilkS" user "Ref Des/Silkscreen Bottom")
		(1 "F.Mask" user "Board Geometry/Soldermask Top")
		(3 "B.Mask" user "Board Geometry/Soldermask Bottom")
		(17 "Dwgs.User" user "User.Drawings")
		(19 "Cmts.User" user "User.Comments")
		(21 "Eco1.User" user "User.Eco1")
		(23 "Eco2.User" user "User.Eco2")
		(25 "Edge.Cuts" user "Board Geometry/Outline")
		(27 "Margin" user)
		(31 "F.CrtYd" user "Package Geometry/Place Bound Top")
		(29 "B.CrtYd" user "Package Geometry/Place Bound Bottom")
		(35 "F.Fab" user "Ref Des/Assembly Top")
		(33 "B.Fab" user "Ref Des/Assembly Bottom")
	)
	(footprint ""
		(layer "B.Cu")
		(at 427.795944 -11.947906 -90)
		(property "Reference" "R1U46"
			(at 0 0 90)
			(layer "B.SilkS")
			(hide yes)
			(effects
				(font
					(size 1.27 1.27)
				)
				(justify mirror)
			)
		)
		(property "Value" ""
			(at 0 0 90)
			(layer "B.Fab")
			(effects
				(font
					(size 1.27 1.27)
				)
				(justify mirror)
			)
		)
		(duplicate_pad_numbers_are_jumpers no)
		(fp_poly
			(pts
				(xy 0.2794 -0.1016) (xy -0.2794 -0.1016) (xy -0.2794 0.9906) (xy 0.2794 0.9906)
			)
			(stroke
				(width 0)
				(type default)
			)
			(fill no)
			(layer "B.CrtYd")
		)
		(fp_line
			(start -0.2794 0.9906)
			(end -0.2794 -0.1016)
			(stroke
				(width 0.1)
				(type default)
			)
			(layer "B.Fab")
		)
		(fp_line
			(start 0.2794 0.9906)
			(end -0.2794 0.9906)
			(stroke
				(width 0.1)
				(type default)
			)
			(layer "B.Fab")
		)
		(fp_line
			(start -0.2794 -0.1016)
			(end 0.2794 -0.1016)
			(stroke
				(width 0.1)
				(type default)
			)
			(layer "B.Fab")
		)
		(fp_line
			(start 0.2794 -0.1016)
			(end 0.2794 0.9906)
			(stroke
				(width 0.1)
				(type default)
			)
			(layer "B.Fab")
		)
		(pad "1" smd rect
			(at 0 0 90)
			(size 0.508 0.508)
			(layers "B.Cu" "B.Mask" "B.Paste")
			(net "H_CPU0_MEMABC_MEMHOT_LVT3_K_N")
		)
		(pad "2" smd rect
			(at 0 0.889 90)
			(size 0.508 0.508)
			(layers "B.Cu" "B.Mask" "B.Paste")
			(net "H_CPU0_MEMABC_MEMHOT_LVT3_N")
		)
		(zone
			(layer "B.Cu")
			(hatch none 0.5)
			(connect_pads
				(clearance 0)
			)
			(min_thickness 0.25)
			(keepout
				(tracks not_allowed)
				(vias allowed)
				(pads allowed)
				(copperpour not_allowed)
				(footprints allowed)
			)
			(placement
				(enabled no)
				(sheetname "")
			)
			(fill
				(thermal_gap 0.5)
				(thermal_bridge_width 0.5)
				(island_removal_mode 0)
			)
			(polygon
				(pts
					(xy 427.160944 -11.693906) (xy 427.160944 -12.201906) (xy 427.541944 -12.201906) (xy 427.541944 -11.693906)
				)
			)
		)
		(zone
			(layer "B.Cu")
			(hatch none 0.5)
			(connect_pads
				(clearance 0)
			)
			(min_thickness 0.25)
			(keepout
				(tracks allowed)
				(vias not_allowed)
				(pads allowed)
				(copperpour not_allowed)
				(footprints allowed)
			)
			(placement
				(enabled no)
				(sheetname "")
			)
			(fill
				(thermal_gap 0.5)
				(thermal_bridge_width 0.5)
				(island_removal_mode 0)
			)
			(polygon
				(pts
					(xy 427.541944 -11.693906) (xy 427.541944 -12.201906) (xy 427.160944 -12.201906) (xy 427.160944 -11.693906)
				)
			)
		)
	)
	(footprint ""
		(layer "B.Cu")
		(at 311.15 -123.8504)
		(property "Reference" ""
			(at 0 0 0)
			(layer "B.SilkS")
			(hide yes)
			(effects
				(font
					(size 1.27 1.27)
				)
				(justify mirror)
			)
		)
		(property "Value" ""
			(at 0 0 0)
			(layer "B.Fab")
			(effects
				(font
					(size 1.27 1.27)
				)
				(justify mirror)
			)
		)
		(duplicate_pad_numbers_are_jumpers no)
		(fp_poly
			(pts
				(arc
					(start 2.032 0)
					(mid -2.032 0)
					(end 2.032 0)
				)
			)
			(stroke
				(width 0)
				(type default)
			)
			(fill no)
			(layer "B.CrtYd")
		)
		(pad "1" smd circle
			(at 0 0 180)
			(size 1.016 1.016)
			(layers "B.Cu" "B.Mask" "B.Paste")
			(net "Net_397")
		)
		(zone
			(layers "F.Cu" "B.Cu" "In1.Cu" "In2.Cu" "In3.Cu" "In4.Cu" "In5.Cu" "In6.Cu"
				"In7.Cu" "In8.Cu" "In9.Cu" "In10.Cu" "In11.Cu" "In12.Cu"
			)
			(hatch none 0.5)
			(connect_pads
				(clearance 0)
			)
			(min_thickness 0.25)
			(keepout
				(tracks allowed)
				(vias not_allowed)
				(pads allowed)
				(copperpour not_allowed)
				(footprints allowed)
			)
			(placement
				(enabled no)
				(sheetname "")
			)
			(fill
				(thermal_gap 0.5)
				(thermal_bridge_width 0.5)
				(island_removal_mode 0)
			)
			(polygon
				(pts
					(arc
						(start 312.674 -123.8504)
						(mid 309.626 -123.8504)
						(end 312.674 -123.8504)
					)
				)
			)
		)
		(zone
			(layer "B.Cu")
			(hatch none 0.5)
			(connect_pads
				(clearance 0)
			)
			(min_thickness 0.25)
			(keepout
				(tracks not_allowed)
				(vias allowed)
				(pads allowed)
				(copperpour not_allowed)
				(footprints allowed)
			)
			(placement
				(enabled no)
				(sheetname "")
			)
			(fill
				(thermal_gap 0.5)
				(thermal_bridge_width 0.5)
				(island_removal_mode 0)
			)
			(polygon
				(pts
					(arc
						(start 312.674 -123.8504)
						(mid 309.626 -123.8504)
						(end 312.674 -123.8504)
					)
				)
			)
		)
	)
	(footprint ""
		(layer "B.Cu")
		(at 489.65739 -148.082 90)
		(property "Reference" "R1L11"
			(at 0 0 90)
			(layer "B.SilkS")
			(hide yes)
			(effects
				(font
					(size 1.27 1.27)
				)
				(justify mirror)
			)
		)
		(property "Value" ""
			(at 0 0 90)
			(layer "B.Fab")
			(effects
				(font
					(size 1.27 1.27)
				)
				(justify mirror)
			)
		)
		(duplicate_pad_numbers_are_jumpers no)
		(fp_poly
			(pts
				(xy 0.2794 -0.1016) (xy -0.2794 -0.1016) (xy -0.2794 0.9906) (xy 0.2794 0.9906)
			)
			(stroke
				(width 0)
				(type default)
			)
			(fill no)
			(layer "B.CrtYd")
		)
		(fp_line
			(start 0.2794 -0.1016)
			(end 0.2794 0.9906)
			(stroke
				(width 0.1)
				(type default)
			)
			(layer "B.Fab")
		)
		(fp_line
			(start -0.2794 -0.1016)
			(end 0.2794 -0.1016)
			(stroke
				(width 0.1)
				(type default)
			)
			(layer "B.Fab")
		)
		(fp_line
			(start 0.2794 0.9906)
			(end -0.2794 0.9906)
			(stroke
				(width 0.1)
				(type default)
			)
			(layer "B.Fab")
		)
		(fp_line
			(start -0.2794 0.9906)
			(end -0.2794 -0.1016)
			(stroke
				(width 0.1)
				(type default)
			)
			(layer "B.Fab")
		)
		(pad "1" smd rect
			(at 0 0 270)
			(size 0.508 0.508)
			(layers "B.Cu" "B.Mask" "B.Paste")
			(net "LED_POSTCODE_7")
		)
		(pad "2" smd rect
			(at 0 0.889 270)
			(size 0.508 0.508)
			(layers "B.Cu" "B.Mask" "B.Paste")
			(net "LED_POSTCODE_7_R")
		)
		(zone
			(layer "B.Cu")
			(hatch none 0.5)
			(connect_pads
				(clearance 0)
			)
			(min_thickness 0.25)
			(keepout
				(tracks allowed)
				(vias not_allowed)
				(pads allowed)
				(copperpour not_allowed)
				(footprints allowed)
			)
			(placement
				(enabled no)
				(sheetname "")
			)
			(fill
				(thermal_gap 0.5)
				(thermal_bridge_width 0.5)
				(island_removal_mode 0)
			)
			(polygon
				(pts
					(xy 489.91139 -148.336) (xy 489.91139 -147.828) (xy 490.29239 -147.828) (xy 490.29239 -148.336)
				)
			)
		)
		(zone
			(layer "B.Cu")
			(hatch none 0.5)
			(connect_pads
				(clearance 0)
			)
			(min_thickness 0.25)
			(keepout
				(tracks not_allowed)
				(vias allowed)
				(pads allowed)
				(copperpour not_allowed)
				(footprints allowed)
			)
			(placement
				(enabled no)
				(sheetname "")
			)
			(fill
				(thermal_gap 0.5)
				(thermal_bridge_width 0.5)
				(island_removal_mode 0)
			)
			(polygon
				(pts
					(xy 490.29239 -148.336) (xy 490.29239 -147.828) (xy 489.91139 -147.828) (xy 489.91139 -148.336)
				)
			)
		)
	)
)
